# BASEBOARD_FAB2 (Tioga Pass) — schematic netlist excerpt (pin names and nets, part order shuffled) for the footprints in the layout excerpt that follows; sources: Cadence DE-HDL packaged netlist, KiCad conversion of Wiwynn_Tioga_Pass_MB.brd

C7P15  CAP  100UF 4V 20% X5R  pkg 0805  page 76 : A = PVCCMCP_CPU1 ; B = GND
R1U16  RES  1.00K 1% CHIP  pkg 0402  page 164 : A = FM_BOARD_SKU_ID1 ; B = GND
C2R16  CAP_A  0.1UF 16V 10% X7R  pkg 0402V  page 188 : A = P12V_STBY ; B = GND

(kicad_pcb
	(version 20260206)
	(generator "pcbnew")
	(generator_version "10.0")
	(general
		(thickness 1.6)
		(legacy_teardrops no)
	)
	(paper "A4")
	(title_block
		(title "Wiwynn_Tioga_Pass_MB.brd")
		(comment 1 "Tioga Pass / footprints 4495-4497 of 4770")
	)
	(layers
		(0 "F.Cu" signal "TOP")
		(4 "In1.Cu" signal "L2GND")
		(6 "In2.Cu" signal "L3")
		(8 "In3.Cu" signal "L4GND")
		(10 "In4.Cu" signal "L5")
		(12 "In5.Cu" signal "L6GND")
		(14 "In6.Cu" signal "L7VCC")
		(16 "In7.Cu" signal "L8VCC")
		(18 "In8.Cu" signal "L9GND")
		(20 "In9.Cu" signal "L10")
		(22 "In10.Cu" signal "L11GND")
		(24 "In11.Cu" signal "L12")
		(26 "In12.Cu" signal "L13GND")
		(2 "B.Cu" signal "BOTTOM")
		(9 "F.Adhes" user "F.Adhesive")
		(11 "B.Adhes" user "B.Adhesive")
		(13 "F.Paste" user "Package Geometry/Pastemask Top")
		(15 "B.Paste" user "Package Geometry/Pastemask Bottom")
		(5 "F.SilkS" user "Ref Des/Silkscreen Top")
		(7 "B.SilkS" user "Ref Des/Silkscreen Bottom")
		(1 "F.Mask" user "Board Geometry/Soldermask Top")
		(3 "B.Mask" user "Board Geometry/Soldermask Bottom")
		(17 "Dwgs.User" user "User.Drawings")
		(19 "Cmts.User" user "User.Comments")
		(21 "Eco1.User" user "User.Eco1")
		(23 "Eco2.User" user "User.Eco2")
		(25 "Edge.Cuts" user "Board Geometry/Outline")
		(27 "Margin" user)
		(31 "F.CrtYd" user "Package Geometry/Place Bound Top")
		(29 "B.CrtYd" user "Package Geometry/Place Bound Bottom")
		(35 "F.Fab" user "Ref Des/Assembly Top")
		(33 "B.Fab" user "Ref Des/Assembly Bottom")
	)
	(footprint ""
		(layer "B.Cu")
		(at 108.178854 -73.51014)
		(property "Reference" "C7P15"
			(at 0 0 0)
			(layer "B.SilkS")
			(hide yes)
			(effects
				(font
					(size 1.27 1.27)
				)
				(justify mirror)
			)
		)
		(property "Value" ""
			(at 0 0 0)
			(layer "B.Fab")
			(effects
				(font
					(size 1.27 1.27)
				)
				(justify mirror)
			)
		)
		(duplicate_pad_numbers_are_jumpers no)
		(fp_poly
			(pts
				(xy 0.7239 -0.2159) (xy -0.7239 -0.2159) (xy -0.7239 1.9939) (xy 0.7239 1.9939)
			)
			(stroke
				(width 0)
				(type default)
			)
			(fill no)
			(layer "B.CrtYd")
		)
		(fp_line
			(start -0.7239 -0.2159)
			(end 0.7239 -0.2159)
			(stroke
				(width 0.1)
				(type default)
			)
			(layer "B.Fab")
		)
		(fp_line
			(start -0.7239 1.9939)
			(end -0.7239 -0.2159)
			(stroke
				(width 0.1)
				(type default)
			)
			(layer "B.Fab")
		)
		(fp_line
			(start 0.7239 -0.2159)
			(end 0.7239 1.9939)
			(stroke
				(width 0.1)
				(type default)
			)
			(layer "B.Fab")
		)
		(fp_line
			(start 0.7239 1.9939)
			(end -0.7239 1.9939)
			(stroke
				(width 0.1)
				(type default)
			)
			(layer "B.Fab")
		)
		(pad "1" smd rect
			(at 0 0 180)
			(size 1.27 1.016)
			(layers "B.Cu" "B.Mask" "B.Paste")
			(net "PVCCMCP_CPU1")
		)
		(pad "2" smd rect
			(at 0 1.778 180)
			(size 1.27 1.016)
			(layers "B.Cu" "B.Mask" "B.Paste")
			(net "GND")
		)
		(zone
			(layer "B.Cu")
			(hatch none 0.5)
			(connect_pads
				(clearance 0)
			)
			(min_thickness 0.25)
			(keepout
				(tracks not_allowed)
				(vias allowed)
				(pads allowed)
				(copperpour not_allowed)
				(footprints allowed)
			)
			(placement
				(enabled no)
				(sheetname "")
			)
			(fill
				(thermal_gap 0.5)
				(thermal_bridge_width 0.5)
				(island_removal_mode 0)
			)
			(polygon
				(pts
					(xy 108.813854 -73.00214) (xy 107.543854 -73.00214) (xy 107.543854 -72.24014) (xy 108.813854 -72.24014)
				)
			)
		)
	)
	(footprint ""
		(layer "B.Cu")
		(at 428.8409 -17.272 -90)
		(property "Reference" "R1U16"
			(at 0 0 90)
			(layer "B.SilkS")
			(hide yes)
			(effects
				(font
					(size 1.27 1.27)
				)
				(justify mirror)
			)
		)
		(property "Value" ""
			(at 0 0 90)
			(layer "B.Fab")
			(effects
				(font
					(size 1.27 1.27)
				)
				(justify mirror)
			)
		)
		(duplicate_pad_numbers_are_jumpers no)
		(fp_poly
			(pts
				(xy 0.2794 -0.1016) (xy -0.2794 -0.1016) (xy -0.2794 0.9906) (xy 0.2794 0.9906)
			)
			(stroke
				(width 0)
				(type default)
			)
			(fill no)
			(layer "B.CrtYd")
		)
		(fp_line
			(start -0.2794 0.9906)
			(end -0.2794 -0.1016)
			(stroke
				(width 0.1)
				(type default)
			)
			(layer "B.Fab")
		)
		(fp_line
			(start 0.2794 0.9906)
			(end -0.2794 0.9906)
			(stroke
				(width 0.1)
				(type default)
			)
			(layer "B.Fab")
		)
		(fp_line
			(start -0.2794 -0.1016)
			(end 0.2794 -0.1016)
			(stroke
				(width 0.1)
				(type default)
			)
			(layer "B.Fab")
		)
		(fp_line
			(start 0.2794 -0.1016)
			(end 0.2794 0.9906)
			(stroke
				(width 0.1)
				(type default)
			)
			(layer "B.Fab")
		)
		(pad "1" smd rect
			(at 0 0 90)
			(size 0.508 0.508)
			(layers "B.Cu" "B.Mask" "B.Paste")
			(net "FM_BOARD_SKU_ID1")
		)
		(pad "2" smd rect
			(at 0 0.889 90)
			(size 0.508 0.508)
			(layers "B.Cu" "B.Mask" "B.Paste")
			(net "GND")
		)
		(zone
			(layer "B.Cu")
			(hatch none 0.5)
			(connect_pads
				(clearance 0)
			)
			(min_thickness 0.25)
			(keepout
				(tracks not_allowed)
				(vias allowed)
				(pads allowed)
				(copperpour not_allowed)
				(footprints allowed)
			)
			(placement
				(enabled no)
				(sheetname "")
			)
			(fill
				(thermal_gap 0.5)
				(thermal_bridge_width 0.5)
				(island_removal_mode 0)
			)
			(polygon
				(pts
					(xy 428.2059 -17.018) (xy 428.2059 -17.526) (xy 428.5869 -17.526) (xy 428.5869 -17.018)
				)
			)
		)
		(zone
			(layer "B.Cu")
			(hatch none 0.5)
			(connect_pads
				(clearance 0)
			)
			(min_thickness 0.25)
			(keepout
				(tracks allowed)
				(vias not_allowed)
				(pads allowed)
				(copperpour not_allowed)
				(footprints allowed)
			)
			(placement
				(enabled no)
				(sheetname "")
			)
			(fill
				(thermal_gap 0.5)
				(thermal_bridge_width 0.5)
				(island_removal_mode 0)
			)
			(polygon
				(pts
					(xy 428.5869 -17.018) (xy 428.5869 -17.526) (xy 428.2059 -17.526) (xy 428.2059 -17.018)
				)
			)
		)
	)
	(footprint ""
		(layer "B.Cu")
		(at 438.404 -52.3875)
		(property "Reference" "C2R16"
			(at 0 0 0)
			(layer "B.SilkS")
			(hide yes)
			(effects
				(font
					(size 1.27 1.27)
				)
				(justify mirror)
			)
		)
		(property "Value" ""
			(at 0 0 0)
			(layer "B.Fab")
			(effects
				(font
					(size 1.27 1.27)
				)
				(justify mirror)
			)
		)
		(duplicate_pad_numbers_are_jumpers no)
		(fp_poly
			(pts
				(xy -0.3048 -0.1016) (xy -0.3048 0.9906) (xy 0.3048 0.9906) (xy 0.3048 -0.1016)
			)
			(stroke
				(width 0)
				(type default)
			)
			(fill no)
			(layer "B.CrtYd")
		)
		(fp_line
			(start -0.3048 -0.1016)
			(end 0.3048 -0.1016)
			(stroke
				(width 0.1)
				(type default)
			)
			(layer "B.Fab")
		)
		(fp_line
			(start -0.3048 0.9906)
			(end -0.3048 -0.1016)
			(stroke
				(width 0.1)
				(type default)
			)
			(layer "B.Fab")
		)
		(fp_line
			(start 0.3048 -0.1016)
			(end 0.3048 0.9906)
			(stroke
				(width 0.1)
				(type default)
			)
			(layer "B.Fab")
		)
		(fp_line
			(start 0.3048 0.9906)
			(end -0.3048 0.9906)
			(stroke
				(width 0.1)
				(type default)
			)
			(layer "B.Fab")
		)
		(pad "1" smd rect
			(at 0 0 180)
			(size 0.508 0.508)
			(layers "B.Cu" "B.Mask" "B.Paste")
			(net "P12V_STBY")
		)
		(pad "2" smd rect
			(at 0 0.889 180)
			(size 0.508 0.508)
			(layers "B.Cu" "B.Mask" "B.Paste")
			(net "GND")
		)
		(zone
			(layer "B.Cu")
			(hatch none 0.5)
			(connect_pads
				(clearance 0)
			)
			(min_thickness 0.25)
			(keepout
				(tracks allowed)
				(vias not_allowed)
				(pads allowed)
				(copperpour not_allowed)
				(footprints allowed)
			)
			(placement
				(enabled no)
				(sheetname "")
			)
			(fill
				(thermal_gap 0.5)
				(thermal_bridge_width 0.5)
				(island_removal_mode 0)
			)
			(polygon
				(pts
					(xy 438.658 -52.1335) (xy 438.15 -52.1335) (xy 438.15 -51.7525) (xy 438.658 -51.7525)
				)
			)
		)
		(zone
			(layer "B.Cu")
			(hatch none 0.5)
			(connect_pads
				(clearance 0)
			)
			(min_thickness 0.25)
			(keepout
				(tracks not_allowed)
				(vias allowed)
				(pads allowed)
				(copperpour not_allowed)
				(footprints allowed)
			)
			(placement
				(enabled no)
				(sheetname "")
			)
			(fill
				(thermal_gap 0.5)
				(thermal_bridge_width 0.5)
				(island_removal_mode 0)
			)
			(polygon
				(pts
					(xy 438.658 -51.7525) (xy 438.15 -51.7525) (xy 438.15 -52.1335) (xy 438.658 -52.1335)
				)
			)
		)
	)
)
